(kicad_pcb
	(version 20260206)
	(generator "pcbnew")
	(generator_version "10.0")
	(general
		(thickness 1.6)
		(legacy_teardrops no)
	)
	(paper "A4")
	(title_block
		(title "03242023_DA0F0TMBIJ0_F0T_Motherboard_J_brd_V01_OCP.brd")
		(comment 1 "Grand Teton / footprints 3857-3863 of 6105")
	)
	(layers
		(0 "F.Cu" signal "TOP")
		(4 "In1.Cu" signal "GND")
		(6 "In2.Cu" signal "IN1")
		(8 "In3.Cu" signal "GND1")
		(10 "In4.Cu" signal "IN2")
		(12 "In5.Cu" signal "GND2")
		(14 "In6.Cu" signal "IN3")
		(16 "In7.Cu" signal "GND3")
		(18 "In8.Cu" signal "VCC")
		(20 "In9.Cu" signal "VCC1")
		(22 "In10.Cu" signal "GND4")
		(24 "In11.Cu" signal "IN4")
		(26 "In12.Cu" signal "GND5")
		(28 "In13.Cu" signal "IN5")
		(30 "In14.Cu" signal "GND6")
		(32 "In15.Cu" signal "IN6")
		(34 "In16.Cu" signal "GND7")
		(2 "B.Cu" signal "BOTTOM")
		(9 "F.Adhes" user "F.Adhesive")
		(11 "B.Adhes" user "B.Adhesive")
		(13 "F.Paste" user "Package Geometry/Pastemask Top")
		(15 "B.Paste" user "Package Geometry/Pastemask Bottom")
		(5 "F.SilkS" user "Ref Des/Silkscreen Top")
		(7 "B.SilkS" user "Ref Des/Silkscreen Bottom")
		(1 "F.Mask" user "Board Geometry/Soldermask Top")
		(3 "B.Mask" user "Board Geometry/Soldermask Bottom")
		(17 "Dwgs.User" user "User.Drawings")
		(19 "Cmts.User" user "User.Comments")
		(21 "Eco1.User" user "User.Eco1")
		(23 "Eco2.User" user "User.Eco2")
		(25 "Edge.Cuts" user "Board Geometry/Outline")
		(27 "Margin" user)
		(31 "F.CrtYd" user "Package Geometry/Place Bound Top")
		(29 "B.CrtYd" user "Package Geometry/Place Bound Bottom")
		(35 "F.Fab" user "Ref Des/Assembly Top")
		(33 "B.Fab" user "Ref Des/Assembly Bottom")
	)
	(footprint ""
		(layer "F.Cu")
		(at 176.17948 -426.430948 180)
		(property "Reference" "R2820"
			(at 0 0 180)
			(layer "F.SilkS")
			(hide yes)
			(effects
				(font
					(size 1.27 1.27)
				)
			)
		)
		(property "Value" ""
			(at 0 0 180)
			(layer "F.Fab")
			(effects
				(font
					(size 1.27 1.27)
				)
			)
		)
		(duplicate_pad_numbers_are_jumpers no)
		(fp_line
			(start 0.7874 0.4064)
			(end -0.7874 0.4064)
			(stroke
				(width 0.1524)
				(type default)
			)
			(layer "F.SilkS")
		)
		(fp_line
			(start 0.7874 -0.4064)
			(end 0.7874 0.4064)
			(stroke
				(width 0.1524)
				(type default)
			)
			(layer "F.SilkS")
		)
		(fp_line
			(start -0.7874 0.4064)
			(end -0.7874 -0.4064)
			(stroke
				(width 0.1524)
				(type default)
			)
			(layer "F.SilkS")
		)
		(fp_line
			(start -0.7874 -0.4064)
			(end 0.7874 -0.4064)
			(stroke
				(width 0.1524)
				(type default)
			)
			(layer "F.SilkS")
		)
		(fp_line
			(start 0.67945 0.3048)
			(end 0.120396 0.3048)
			(stroke
				(width 0.1)
				(type default)
			)
			(layer "F.Fab")
		)
		(fp_line
			(start 0.67945 -0.3048)
			(end 0.67945 0.3048)
			(stroke
				(width 0.1)
				(type default)
			)
			(layer "F.Fab")
		)
		(fp_line
			(start 0.12065 -0.2794)
			(end 0.12065 -0.3048)
			(stroke
				(width 0.1)
				(type default)
			)
			(layer "F.Fab")
		)
		(fp_line
			(start 0.12065 -0.3048)
			(end 0.67945 -0.3048)
			(stroke
				(width 0.1)
				(type default)
			)
			(layer "F.Fab")
		)
		(fp_line
			(start 0.120396 0.3048)
			(end 0.120396 0.2794)
			(stroke
				(width 0.1)
				(type default)
			)
			(layer "F.Fab")
		)
		(fp_line
			(start 0.120396 0.2794)
			(end -0.12065 0.2794)
			(stroke
				(width 0.1)
				(type default)
			)
			(layer "F.Fab")
		)
		(fp_line
			(start -0.12065 0.3048)
			(end -0.67945 0.3048)
			(stroke
				(width 0.1)
				(type default)
			)
			(layer "F.Fab")
		)
		(fp_line
			(start -0.12065 0.2794)
			(end -0.12065 0.3048)
			(stroke
				(width 0.1)
				(type default)
			)
			(layer "F.Fab")
		)
		(fp_line
			(start -0.12065 -0.2794)
			(end 0.12065 -0.2794)
			(stroke
				(width 0.1)
				(type default)
			)
			(layer "F.Fab")
		)
		(fp_line
			(start -0.12065 -0.305054)
			(end -0.12065 -0.2794)
			(stroke
				(width 0.1)
				(type default)
			)
			(layer "F.Fab")
		)
		(fp_line
			(start -0.67945 0.3048)
			(end -0.67945 -0.305054)
			(stroke
				(width 0.1)
				(type default)
			)
			(layer "F.Fab")
		)
		(fp_line
			(start -0.67945 -0.305054)
			(end -0.12065 -0.305054)
			(stroke
				(width 0.1)
				(type default)
			)
			(layer "F.Fab")
		)
		(pad "1" smd circle
			(at -0.40005 0 180)
			(size 0 0)
			(layers "F.Cu" "F.Mask" "F.Paste")
			(net "P3V3_AUX")
		)
		(pad "2" smd circle
			(at 0.40005 0 180)
			(size 0 0)
			(layers "F.Cu" "F.Mask" "F.Paste")
			(net "BMC_MONITER_BUF_R")
		)
	)
	(footprint ""
		(layer "F.Cu")
		(at 240.00841 -46.967648 180)
		(property "Reference" "R2317"
			(at 0 0 180)
			(layer "F.SilkS")
			(hide yes)
			(effects
				(font
					(size 1.27 1.27)
				)
			)
		)
		(property "Value" ""
			(at 0 0 180)
			(layer "F.Fab")
			(effects
				(font
					(size 1.27 1.27)
				)
			)
		)
		(duplicate_pad_numbers_are_jumpers no)
		(fp_line
			(start 0.7874 0.4064)
			(end -0.7874 0.4064)
			(stroke
				(width 0.1524)
				(type default)
			)
			(layer "F.SilkS")
		)
		(fp_line
			(start 0.7874 -0.4064)
			(end 0.7874 0.4064)
			(stroke
				(width 0.1524)
				(type default)
			)
			(layer "F.SilkS")
		)
		(fp_line
			(start -0.7874 0.4064)
			(end -0.7874 -0.4064)
			(stroke
				(width 0.1524)
				(type default)
			)
			(layer "F.SilkS")
		)
		(fp_line
			(start -0.7874 -0.4064)
			(end 0.7874 -0.4064)
			(stroke
				(width 0.1524)
				(type default)
			)
			(layer "F.SilkS")
		)
		(fp_line
			(start 0.67945 0.3048)
			(end 0.120396 0.3048)
			(stroke
				(width 0.1)
				(type default)
			)
			(layer "F.Fab")
		)
		(fp_line
			(start 0.67945 -0.3048)
			(end 0.67945 0.3048)
			(stroke
				(width 0.1)
				(type default)
			)
			(layer "F.Fab")
		)
		(fp_line
			(start 0.12065 -0.2794)
			(end 0.12065 -0.3048)
			(stroke
				(width 0.1)
				(type default)
			)
			(layer "F.Fab")
		)
		(fp_line
			(start 0.12065 -0.3048)
			(end 0.67945 -0.3048)
			(stroke
				(width 0.1)
				(type default)
			)
			(layer "F.Fab")
		)
		(fp_line
			(start 0.120396 0.3048)
			(end 0.120396 0.2794)
			(stroke
				(width 0.1)
				(type default)
			)
			(layer "F.Fab")
		)
		(fp_line
			(start 0.120396 0.2794)
			(end -0.12065 0.2794)
			(stroke
				(width 0.1)
				(type default)
			)
			(layer "F.Fab")
		)
		(fp_line
			(start -0.12065 0.3048)
			(end -0.67945 0.3048)
			(stroke
				(width 0.1)
				(type default)
			)
			(layer "F.Fab")
		)
		(fp_line
			(start -0.12065 0.2794)
			(end -0.12065 0.3048)
			(stroke
				(width 0.1)
				(type default)
			)
			(layer "F.Fab")
		)
		(fp_line
			(start -0.12065 -0.2794)
			(end 0.12065 -0.2794)
			(stroke
				(width 0.1)
				(type default)
			)
			(layer "F.Fab")
		)
		(fp_line
			(start -0.12065 -0.305054)
			(end -0.12065 -0.2794)
			(stroke
				(width 0.1)
				(type default)
			)
			(layer "F.Fab")
		)
		(fp_line
			(start -0.67945 0.3048)
			(end -0.67945 -0.305054)
			(stroke
				(width 0.1)
				(type default)
			)
			(layer "F.Fab")
		)
		(fp_line
			(start -0.67945 -0.305054)
			(end -0.12065 -0.305054)
			(stroke
				(width 0.1)
				(type default)
			)
			(layer "F.Fab")
		)
		(pad "1" smd circle
			(at -0.40005 0 180)
			(size 0 0)
			(layers "F.Cu" "F.Mask" "F.Paste")
			(net "P3V3_E1S_0")
		)
		(pad "2" smd circle
			(at 0.40005 0 180)
			(size 0 0)
			(layers "F.Cu" "F.Mask" "F.Paste")
			(net "PU_E1S_0_DUALPORT_EN_N")
		)
	)
	(footprint ""
		(layer "F.Cu")
		(at 24.046942 -414.111948)
		(property "Reference" "R2935"
			(at 0 0 0)
			(layer "F.SilkS")
			(hide yes)
			(effects
				(font
					(size 1.27 1.27)
				)
			)
		)
		(property "Value" ""
			(at 0 0 0)
			(layer "F.Fab")
			(effects
				(font
					(size 1.27 1.27)
				)
			)
		)
		(duplicate_pad_numbers_are_jumpers no)
		(fp_line
			(start -0.7874 -0.4064)
			(end 0.7874 -0.4064)
			(stroke
				(width 0.1524)
				(type default)
			)
			(layer "F.SilkS")
		)
		(fp_line
			(start -0.7874 0.4064)
			(end -0.7874 -0.4064)
			(stroke
				(width 0.1524)
				(type default)
			)
			(layer "F.SilkS")
		)
		(fp_line
			(start 0.7874 -0.4064)
			(end 0.7874 0.4064)
			(stroke
				(width 0.1524)
				(type default)
			)
			(layer "F.SilkS")
		)
		(fp_line
			(start 0.7874 0.4064)
			(end -0.7874 0.4064)
			(stroke
				(width 0.1524)
				(type default)
			)
			(layer "F.SilkS")
		)
		(fp_line
			(start -0.67945 -0.305054)
			(end -0.12065 -0.305054)
			(stroke
				(width 0.1)
				(type default)
			)
			(layer "F.Fab")
		)
		(fp_line
			(start -0.67945 0.3048)
			(end -0.67945 -0.305054)
			(stroke
				(width 0.1)
				(type default)
			)
			(layer "F.Fab")
		)
		(fp_line
			(start -0.12065 -0.305054)
			(end -0.12065 -0.2794)
			(stroke
				(width 0.1)
				(type default)
			)
			(layer "F.Fab")
		)
		(fp_line
			(start -0.12065 -0.2794)
			(end 0.12065 -0.2794)
			(stroke
				(width 0.1)
				(type default)
			)
			(layer "F.Fab")
		)
		(fp_line
			(start -0.12065 0.2794)
			(end -0.12065 0.3048)
			(stroke
				(width 0.1)
				(type default)
			)
			(layer "F.Fab")
		)
		(fp_line
			(start -0.12065 0.3048)
			(end -0.67945 0.3048)
			(stroke
				(width 0.1)
				(type default)
			)
			(layer "F.Fab")
		)
		(fp_line
			(start 0.120396 0.2794)
			(end -0.12065 0.2794)
			(stroke
				(width 0.1)
				(type default)
			)
			(layer "F.Fab")
		)
		(fp_line
			(start 0.120396 0.3048)
			(end 0.120396 0.2794)
			(stroke
				(width 0.1)
				(type default)
			)
			(layer "F.Fab")
		)
		(fp_line
			(start 0.12065 -0.3048)
			(end 0.67945 -0.3048)
			(stroke
				(width 0.1)
				(type default)
			)
			(layer "F.Fab")
		)
		(fp_line
			(start 0.12065 -0.2794)
			(end 0.12065 -0.3048)
			(stroke
				(width 0.1)
				(type default)
			)
			(layer "F.Fab")
		)
		(fp_line
			(start 0.67945 -0.3048)
			(end 0.67945 0.3048)
			(stroke
				(width 0.1)
				(type default)
			)
			(layer "F.Fab")
		)
		(fp_line
			(start 0.67945 0.3048)
			(end 0.120396 0.3048)
			(stroke
				(width 0.1)
				(type default)
			)
			(layer "F.Fab")
		)
		(pad "1" smd circle
			(at -0.40005 0)
			(size 0 0)
			(layers "F.Cu" "F.Mask" "F.Paste")
			(net "P3V3_AUX")
		)
		(pad "2" smd circle
			(at 0.40005 0)
			(size 0 0)
			(layers "F.Cu" "F.Mask" "F.Paste")
			(net "FM_GPU_PWRGD_ISO")
		)
	)
	(footprint ""
		(layer "F.Cu")
		(at 122.292872 -357.11638 90)
		(property "Reference" "PR1314"
			(at 0 0 90)
			(layer "F.SilkS")
			(hide yes)
			(effects
				(font
					(size 1.27 1.27)
				)
			)
		)
		(property "Value" ""
			(at 0 0 90)
			(layer "F.Fab")
			(effects
				(font
					(size 1.27 1.27)
				)
			)
		)
		(duplicate_pad_numbers_are_jumpers no)
		(fp_line
			(start 0.7874 -0.4064)
			(end 0.7874 0.4064)
			(stroke
				(width 0.1524)
				(type default)
			)
			(layer "F.SilkS")
		)
		(fp_line
			(start -0.7874 -0.4064)
			(end 0.7874 -0.4064)
			(stroke
				(width 0.1524)
				(type default)
			)
			(layer "F.SilkS")
		)
		(fp_line
			(start 0.7874 0.4064)
			(end -0.7874 0.4064)
			(stroke
				(width 0.1524)
				(type default)
			)
			(layer "F.SilkS")
		)
		(fp_line
			(start -0.7874 0.4064)
			(end -0.7874 -0.4064)
			(stroke
				(width 0.1524)
				(type default)
			)
			(layer "F.SilkS")
		)
		(fp_line
			(start -0.12065 -0.305054)
			(end -0.12065 -0.2794)
			(stroke
				(width 0.1)
				(type default)
			)
			(layer "F.Fab")
		)
		(fp_line
			(start -0.67945 -0.305054)
			(end -0.12065 -0.305054)
			(stroke
				(width 0.1)
				(type default)
			)
			(layer "F.Fab")
		)
		(fp_line
			(start 0.67945 -0.3048)
			(end 0.67945 0.3048)
			(stroke
				(width 0.1)
				(type default)
			)
			(layer "F.Fab")
		)
		(fp_line
			(start 0.12065 -0.3048)
			(end 0.67945 -0.3048)
			(stroke
				(width 0.1)
				(type default)
			)
			(layer "F.Fab")
		)
		(fp_line
			(start 0.12065 -0.2794)
			(end 0.12065 -0.3048)
			(stroke
				(width 0.1)
				(type default)
			)
			(layer "F.Fab")
		)
		(fp_line
			(start -0.12065 -0.2794)
			(end 0.12065 -0.2794)
			(stroke
				(width 0.1)
				(type default)
			)
			(layer "F.Fab")
		)
		(fp_line
			(start 0.120396 0.2794)
			(end -0.12065 0.2794)
			(stroke
				(width 0.1)
				(type default)
			)
			(layer "F.Fab")
		)
		(fp_line
			(start -0.12065 0.2794)
			(end -0.12065 0.3048)
			(stroke
				(width 0.1)
				(type default)
			)
			(layer "F.Fab")
		)
		(fp_line
			(start 0.67945 0.3048)
			(end 0.120396 0.3048)
			(stroke
				(width 0.1)
				(type default)
			)
			(layer "F.Fab")
		)
		(fp_line
			(start 0.120396 0.3048)
			(end 0.120396 0.2794)
			(stroke
				(width 0.1)
				(type default)
			)
			(layer "F.Fab")
		)
		(fp_line
			(start -0.12065 0.3048)
			(end -0.67945 0.3048)
			(stroke
				(width 0.1)
				(type default)
			)
			(layer "F.Fab")
		)
		(fp_line
			(start -0.67945 0.3048)
			(end -0.67945 -0.305054)
			(stroke
				(width 0.1)
				(type default)
			)
			(layer "F.Fab")
		)
		(pad "1" smd circle
			(at -0.40005 0 90)
			(size 0 0)
			(layers "F.Cu" "F.Mask" "F.Paste")
			(net "PVPP_HBM_CPU1_FB")
		)
		(pad "2" smd circle
			(at 0.40005 0 90)
			(size 0 0)
			(layers "F.Cu" "F.Mask" "F.Paste")
			(net "SH_PVPP_HBM_CPU1_N")
		)
	)
	(footprint ""
		(layer "F.Cu")
		(at 382.005332 -71.134224 180)
		(property "Reference" "PR395"
			(at 0 0 180)
			(layer "F.SilkS")
			(hide yes)
			(effects
				(font
					(size 1.27 1.27)
				)
			)
		)
		(property "Value" ""
			(at 0 0 180)
			(layer "F.Fab")
			(effects
				(font
					(size 1.27 1.27)
				)
			)
		)
		(duplicate_pad_numbers_are_jumpers no)
		(fp_line
			(start 0.7874 0.4064)
			(end -0.7874 0.4064)
			(stroke
				(width 0.1524)
				(type default)
			)
			(layer "F.SilkS")
		)
		(fp_line
			(start 0.7874 -0.4064)
			(end 0.7874 0.4064)
			(stroke
				(width 0.1524)
				(type default)
			)
			(layer "F.SilkS")
		)
		(fp_line
			(start -0.7874 0.4064)
			(end -0.7874 -0.4064)
			(stroke
				(width 0.1524)
				(type default)
			)
			(layer "F.SilkS")
		)
		(fp_line
			(start -0.7874 -0.4064)
			(end 0.7874 -0.4064)
			(stroke
				(width 0.1524)
				(type default)
			)
			(layer "F.SilkS")
		)
		(fp_line
			(start 0.67945 0.3048)
			(end 0.120396 0.3048)
			(stroke
				(width 0.1)
				(type default)
			)
			(layer "F.Fab")
		)
		(fp_line
			(start 0.67945 -0.3048)
			(end 0.67945 0.3048)
			(stroke
				(width 0.1)
				(type default)
			)
			(layer "F.Fab")
		)
		(fp_line
			(start 0.12065 -0.2794)
			(end 0.12065 -0.3048)
			(stroke
				(width 0.1)
				(type default)
			)
			(layer "F.Fab")
		)
		(fp_line
			(start 0.12065 -0.3048)
			(end 0.67945 -0.3048)
			(stroke
				(width 0.1)
				(type default)
			)
			(layer "F.Fab")
		)
		(fp_line
			(start 0.120396 0.3048)
			(end 0.120396 0.2794)
			(stroke
				(width 0.1)
				(type default)
			)
			(layer "F.Fab")
		)
		(fp_line
			(start 0.120396 0.2794)
			(end -0.12065 0.2794)
			(stroke
				(width 0.1)
				(type default)
			)
			(layer "F.Fab")
		)
		(fp_line
			(start -0.12065 0.3048)
			(end -0.67945 0.3048)
			(stroke
				(width 0.1)
				(type default)
			)
			(layer "F.Fab")
		)
		(fp_line
			(start -0.12065 0.2794)
			(end -0.12065 0.3048)
			(stroke
				(width 0.1)
				(type default)
			)
			(layer "F.Fab")
		)
		(fp_line
			(start -0.12065 -0.2794)
			(end 0.12065 -0.2794)
			(stroke
				(width 0.1)
				(type default)
			)
			(layer "F.Fab")
		)
		(fp_line
			(start -0.12065 -0.305054)
			(end -0.12065 -0.2794)
			(stroke
				(width 0.1)
				(type default)
			)
			(layer "F.Fab")
		)
		(fp_line
			(start -0.67945 0.3048)
			(end -0.67945 -0.305054)
			(stroke
				(width 0.1)
				(type default)
			)
			(layer "F.Fab")
		)
		(fp_line
			(start -0.67945 -0.305054)
			(end -0.12065 -0.305054)
			(stroke
				(width 0.1)
				(type default)
			)
			(layer "F.Fab")
		)
		(pad "1" smd circle
			(at -0.40005 0 180)
			(size 0 0)
			(layers "F.Cu" "F.Mask" "F.Paste")
			(net "P3V3_AUX")
		)
		(pad "2" smd circle
			(at 0.40005 0 180)
			(size 0 0)
			(layers "F.Cu" "F.Mask" "F.Paste")
			(net "PVCC1_AUX")
		)
	)
	(footprint ""
		(layer "F.Cu")
		(at 61.778896 -70.78599)
		(property "Reference" "D71"
			(at -33.207706 50.178462 90)
			(unlocked yes)
			(layer "F.SilkS")
			(effects
				(font
					(size 0.635 0.4064)
					(thickness 0.1524)
				)
				(justify left)
			)
		)
		(property "Value" ""
			(at 0 0 0)
			(layer "F.Fab")
			(effects
				(font
					(size 1.27 1.27)
				)
			)
		)
		(duplicate_pad_numbers_are_jumpers no)
		(fp_line
			(start -0.90678 0.4826)
			(end -0.90678 -0.4699)
			(stroke
				(width 0.1524)
				(type default)
			)
			(layer "F.SilkS")
		)
		(fp_line
			(start -0.89408 -0.4826)
			(end 0.90678 -0.4826)
			(stroke
				(width 0.1524)
				(type default)
			)
			(layer "F.SilkS")
		)
		(fp_line
			(start -0.79248 -0.4826)
			(end 1.03378 -0.4826)
			(stroke
				(width 0.1524)
				(type default)
			)
			(layer "F.SilkS")
		)
		(fp_line
			(start -0.64008 -0.4826)
			(end 1.16078 -0.4826)
			(stroke
				(width 0.1524)
				(type default)
			)
			(layer "F.SilkS")
		)
		(fp_line
			(start 0.90678 -0.4826)
			(end 0.90678 0.4826)
			(stroke
				(width 0.1524)
				(type default)
			)
			(layer "F.SilkS")
		)
		(fp_line
			(start 0.90678 0.4826)
			(end -0.90678 0.4826)
			(stroke
				(width 0.1524)
				(type default)
			)
			(layer "F.SilkS")
		)
		(fp_line
			(start 1.03378 -0.4826)
			(end 1.03378 0.4826)
			(stroke
				(width 0.1524)
				(type default)
			)
			(layer "F.SilkS")
		)
		(fp_line
			(start 1.03378 0.4826)
			(end -0.79248 0.4826)
			(stroke
				(width 0.1524)
				(type default)
			)
			(layer "F.SilkS")
		)
		(fp_line
			(start 1.16078 -0.4826)
			(end 1.16078 0.4826)
			(stroke
				(width 0.1524)
				(type default)
			)
			(layer "F.SilkS")
		)
		(fp_line
			(start 1.16078 0.4826)
			(end -0.64008 0.4826)
			(stroke
				(width 0.1524)
				(type default)
			)
			(layer "F.SilkS")
		)
		(fp_line
			(start -0.499872 -0.249936)
			(end 0.499872 -0.249936)
			(stroke
				(width 0.1)
				(type default)
			)
			(layer "F.Fab")
		)
		(fp_line
			(start -0.499872 0.249936)
			(end -0.499872 -0.249936)
			(stroke
				(width 0.1)
				(type default)
			)
			(layer "F.Fab")
		)
		(fp_line
			(start 0.499872 -0.249936)
			(end 0.499872 0.249936)
			(stroke
				(width 0.1)
				(type default)
			)
			(layer "F.Fab")
		)
		(fp_line
			(start 0.499872 0.249936)
			(end -0.499872 0.249936)
			(stroke
				(width 0.1)
				(type default)
			)
			(layer "F.Fab")
		)
		(pad "A" smd rect
			(at -0.47498 0)
			(size 0.6096 0.7112)
			(layers "F.Cu" "F.Mask" "F.Paste")
			(net "LED_RST_PLD_CPU1_DRAM_EF_N")
		)
		(pad "C" smd rect
			(at 0.47498 0)
			(size 0.6096 0.7112)
			(layers "F.Cu" "F.Mask" "F.Paste")
			(net "LED_RST_PLD_CPU1_DRAM_EF_N_D")
		)
	)
	(footprint ""
		(layer "F.Cu")
		(at 80.847438 -408.517344 -90)
		(property "Reference" "C689"
			(at 0 0 270)
			(layer "F.SilkS")
			(hide yes)
			(effects
				(font
					(size 1.27 1.27)
				)
			)
		)
		(property "Value" ""
			(at 0 0 270)
			(layer "F.Fab")
			(effects
				(font
					(size 1.27 1.27)
				)
			)
		)
		(duplicate_pad_numbers_are_jumpers no)
		(fp_line
			(start -0.299974 0.150114)
			(end -0.299974 -0.150114)
			(stroke
				(width 0.1)
				(type default)
			)
			(layer "F.Fab")
		)
		(fp_line
			(start 0.299974 0.150114)
			(end -0.299974 0.150114)
			(stroke
				(width 0.1)
				(type default)
			)
			(layer "F.Fab")
		)
		(fp_line
			(start -0.299974 -0.150114)
			(end 0.299974 -0.150114)
			(stroke
				(width 0.1)
				(type default)
			)
			(layer "F.Fab")
		)
		(fp_line
			(start 0.299974 -0.150114)
			(end 0.299974 0.150114)
			(stroke
				(width 0.1)
				(type default)
			)
			(layer "F.Fab")
		)
		(pad "1" smd rect
			(at -0.2667 0 270)
			(size 0.3048 0.381)
			(layers "F.Cu" "F.Mask" "F.Paste")
			(net "P5E_CPU1_PE4_TX_C_DP<10>")
		)
		(pad "2" smd rect
			(at 0.2667 0 270)
			(size 0.3048 0.381)
			(layers "F.Cu" "F.Mask" "F.Paste")
			(net "P5E_CPU1_PE4_TX_DP<10>")
		)
	)
)
